Created on Valor NPI 9.6 Update 2 - Netlist Compare Summary.
DATE :  07 Aug 2017
TIME :  13:52:38


     MISMATCH SUMMARY REPORT
     -----------------------

Job  : 16342-2                 Job  : 16342-2
Step : q                       Step : q
Type : CAD                     Type : CURCAD

-----------------------------------------------

 Mismatch Type: shorted

   GND                   -   NET00000            
   AGND_P1V8_STBY        -    "                  
   AGND_P3V3_STBY        -    "                  
   AGND_P5V              -    "                  
   AGND_CURRENT_MON      -    "                  
   AGND_P3V3_M2          -    "                  
   P5V_STBY              -   NET00009            
   P5V_CC                -    "                  
   P1V8_STBY             -   NET00047            
   P1V8_STBY_CC          -    "                  

 Total : 3
-----------------------------------------------

 Mismatch Type: broken


 Total : 0
-----------------------------------------------

 Mismatch Type: missing


 Total : 0
-----------------------------------------------

 Mismatch Type: extra


 Total : 0
-----------------------------------------------
